FILE_TYPE = CONNECTIVITY;
{Allegro Design Entry HDL 17.2-2016 S081 (4005846) 1/11/2022}
"PAGE_NUMBER" = 166;
0"NC";
1"GND\g";
2"GND\g";
3"GND\g";
4"GND\g";
5"GND\g";
6"GND\g";
7"P1V8_STBY\g";
8"P3V3_STBY\g";
9"P3V3_STBY\g";
10"P5V_STBY\g";
11"PWRGD_P3V3_STBY_R";
12"PWRGD_P1V8_STBY";
13"PWRGD_P1V8_STBY_R";
14"P1V8_STBY_ADJ";
%"UNIVERSAL_GND"
"1","(-1975,-650)","0","pure_quanta_power","I10";
;
HDL_POWER"GND"
CDS_LIB"pure_quanta_power";
"A"5;
%"UNIVERSAL_GND"
"1","(-1575,-650)","0","pure_quanta_power","I12";
;
HDL_POWER"GND"
CDS_LIB"pure_quanta_power";
"A"1;
%"UNIVERSAL_GND"
"1","(-1775,350)","0","pure_quanta_power","I14";
;
HDL_POWER"GND"
CDS_LIB"pure_quanta_power";
"A"2;
%"Q_CAP"
"1","(-1775,575)","0","pure_quanta","I15";
;
LOCATION"C2"
$SEC"1"
CDS_SEC"1"
PACK_TYPE"C0603"
PART_NUMBER"CH6103ME902"
VOLTAGE"16V"
MATERIAL"X6S"
TOLERANCE"20%"
VALUE"10UF"
CDS_LIB"pure_quanta";
"B"
$PN"2"2;
"A"
$PN"1"8;
%"Q_CAP"
"1","(-850,-25)","0","pure_quanta","I16";
;
LOCATION"C3"
$SEC"1"
CDS_SEC"1"
PACK_TYPE"C0402"
VOLTAGE"6.3V"
PART_NUMBER"CH6101MEB01"
VALUE"10UF"
TOLERANCE"20%"
MATERIAL"X6S"
CDS_LIB"pure_quanta";
"B"
$PN"2"6;
"A"
$PN"1"7;
%"UNIVERSAL_GND"
"1","(-475,-400)","0","pure_quanta_power","I17";
;
HDL_POWER"GND"
CDS_LIB"pure_quanta_power";
"A"6;
%"Q_CAP"
"1","(-475,-25)","0","pure_quanta","I18";
;
LOCATION"C58"
$SEC"1"
CDS_SEC"1"
PACK_TYPE"0402"
VOLTAGE"25V"
PART_NUMBER"CH4104K1B00"
VALUE"0.1UF"
TOLERANCE"10%"
MATERIAL"X7R"
CDS_LIB"pure_quanta";
"B"
$PN"2"6;
"A"
$PN"1"7;
%"VCC_CORE"
"1","(-475,250)","0","pure_quanta_power","I19";
;
HDL_POWER"P1V8_STBY"
CDS_LIB"pure_quanta_power";
"A"7;
%"VCC_CORE"
"1","(-1775,900)","0","pure_quanta_power","I20";
;
HDL_POWER"P3V3_STBY"
CDS_LIB"pure_quanta_power";
"A"8;
%"Q_RES"
"1","(-1575,-25)","1","pure_quanta","I21";
;
LOCATION"R3"
$SEC"1"
CDS_SEC"1"
PACK_TYPE"0402LF"
PART_NUMBER"CS31502FB05"
VALUE"15K"
TOLERANCE"1%"
MATERIAL"CHIP"
WATTAGE"1/16W"
CDS_LIB"pure_quanta";
"B"
$PN"2"7;
"A"
$PN"1"14;
%"Q_RES"
"1","(-1575,-425)","1","pure_quanta","I22";
;
LOCATION"R4"
$SEC"1"
CDS_SEC"1"
PACK_TYPE"0402LF"
PART_NUMBER"CS31202FB04"
VALUE"12K"
TOLERANCE"1%"
MATERIAL"CHIP"
WATTAGE"1/16W"
CDS_LIB"pure_quanta";
"B"
$PN"2"14;
"A"
$PN"1"1;
%"UNIVERSAL_GND"
"1","(-4775,-275)","0","pure_quanta_power","I23";
;
HDL_POWER"GND"
CDS_LIB"pure_quanta_power";
"A"3;
%"Q_CAP"
"1","(-4775,-75)","2","pure_quanta","I24";
;
LOCATION"C345"
$SEC"1"
CDS_SEC"1"
TOLERANCE"10%"
MATERIAL"EMPTY"
PART_NUMBER"CH4104K1B00"
PACK_TYPE"0402"
VOLTAGE"25V"
VALUE"0.1UF"
ROOM"VR_DDR0_CTRL"
CDS_LIB"pure_quanta";
"B"
$PN"2"3;
"A"
$PN"1"11;
%"Q_RES"
"1","(-4325,-450)","0","pure_quanta","I25";
;
LOCATION"R214"
$SEC"1"
CDS_SEC"1"
VALUE"33"
ROOM"RST_CPU0_PLD_TO_DIMM"
PACK_TYPE"0402LF"
PART_NUMBER"CS03302JB29"
TOLERANCE"5%"
MATERIAL"CHIP"
WATTAGE"1/16W"
CDS_LIB"pure_quanta"
BOM_COST"MEM";
"B"
$PN"2"12;
"A"
$PN"1"13;
%"VCC_CORE"
"1","(-3875,-200)","0","pure_quanta_power","I3";
;
HDL_POWER"P3V3_STBY"
CDS_LIB"pure_quanta_power";
"A"9;
%"RT9059GQW"
"1","(-2625,50)","0","pure_quanta","I4";
;
LOCATION"U1"
$SEC"1"
CDS_SEC"1"
VALUE"RT9059GQW"
PART_NUMBER"AL009059000"
MATERIAL"IC"
PART_TYPE"SMLF"
CDS_LMAN_SYM_OUTLINE"-250,550,250,-550"
CDS_LIB"pure_quanta"
PIN_NAMES_ROTATE"TRUE";
"VIN3"
$PN"9"8;
"VIN2"
$PN"8"8;
"VOUT3"
$PN"3"7;
"VOUT2"
$PN"2"7;
"EP"
$PN"TH"5;
"VDD"
$PN"10"10;
"VIN1"
$PN"7"8;
"VOUT1"
$PN"1"7;
"ADJ"
$PN"4"14;
"EN"
$PN"6"11;
"PGOOD"
$PN"5"12;
%"Q_RES"
"1","(-3475,-325)","0","pure_quanta","I6";
;
LOCATION"R2"
$SEC"1"
CDS_SEC"1"
VALUE"10K"
TOLERANCE"5%"
PACK_TYPE"0402LF"
WATTAGE"1/16W"
PART_NUMBER"TMP_QCS31002JB28"
MATERIAL"CHIP"
CDS_LIB"pure_quanta";
"B"
$PN"2"12;
"A"
$PN"1"9;
%"UNIVERSAL_GND"
"1","(-3400,200)","0","pure_quanta_power","I7";
;
HDL_POWER"GND"
CDS_LIB"pure_quanta_power";
"A"4;
%"Q_CAP"
"1","(-3400,400)","0","pure_quanta","I8";
;
LOCATION"C1"
$SEC"1"
CDS_SEC"1"
VALUE"1UF"
PART_NUMBER"CH5104KEB02"
MATERIAL"X6S"
PACK_TYPE"C0402"
VOLTAGE"25V"
TOLERANCE"10%"
CDS_LIB"pure_quanta";
"B"
$PN"2"4;
"A"
$PN"1"10;
%"VCC_CORE"
"1","(-3400,675)","0","pure_quanta_power","I9";
;
HDL_POWER"P5V_STBY"
CDS_LIB"pure_quanta_power";
"A"10;
END.
